# BASEBOARD_FAB2 (Tioga Pass) — schematic netlist excerpt (pin names and nets, part order shuffled) for the footprints in the layout excerpt that follows; sources: Cadence DE-HDL packaged netlist, KiCad conversion of Wiwynn_Tioga_Pass_MB.brd

C2T38  CAP_A  1.0UF 6.3V 10% X6S  pkg 0402V  page 101 : A = P3V3_STBY_MNG_RMII ; B = GND
C2R18  CAP_A  0.1UF 16V 10% X7R  pkg 0402V  page 188 : A = P12V_STBY ; B = GND
R4C5  RES  100.0 1% CHIP  pkg 0402  page 205 : A = VSENSE_PVSA_CPU0_P ; B = PVSA_CPU0

(kicad_pcb
	(version 20260206)
	(generator "pcbnew")
	(generator_version "10.0")
	(general
		(thickness 1.6)
		(legacy_teardrops no)
	)
	(paper "A4")
	(title_block
		(title "Wiwynn_Tioga_Pass_MB.brd")
		(comment 1 "Tioga Pass / footprints 3468-3470 of 4770")
	)
	(layers
		(0 "F.Cu" signal "TOP")
		(4 "In1.Cu" signal "L2GND")
		(6 "In2.Cu" signal "L3")
		(8 "In3.Cu" signal "L4GND")
		(10 "In4.Cu" signal "L5")
		(12 "In5.Cu" signal "L6GND")
		(14 "In6.Cu" signal "L7VCC")
		(16 "In7.Cu" signal "L8VCC")
		(18 "In8.Cu" signal "L9GND")
		(20 "In9.Cu" signal "L10")
		(22 "In10.Cu" signal "L11GND")
		(24 "In11.Cu" signal "L12")
		(26 "In12.Cu" signal "L13GND")
		(2 "B.Cu" signal "BOTTOM")
		(9 "F.Adhes" user "F.Adhesive")
		(11 "B.Adhes" user "B.Adhesive")
		(13 "F.Paste" user "Package Geometry/Pastemask Top")
		(15 "B.Paste" user "Package Geometry/Pastemask Bottom")
		(5 "F.SilkS" user "Ref Des/Silkscreen Top")
		(7 "B.SilkS" user "Ref Des/Silkscreen Bottom")
		(1 "F.Mask" user "Board Geometry/Soldermask Top")
		(3 "B.Mask" user "Board Geometry/Soldermask Bottom")
		(17 "Dwgs.User" user "User.Drawings")
		(19 "Cmts.User" user "User.Comments")
		(21 "Eco1.User" user "User.Eco1")
		(23 "Eco2.User" user "User.Eco2")
		(25 "Edge.Cuts" user "Board Geometry/Outline")
		(27 "Margin" user)
		(31 "F.CrtYd" user "Package Geometry/Place Bound Top")
		(29 "B.CrtYd" user "Package Geometry/Place Bound Bottom")
		(35 "F.Fab" user "Ref Des/Assembly Top")
		(33 "B.Fab" user "Ref Des/Assembly Bottom")
	)
	(footprint ""
		(layer "B.Cu")
		(at 476.885 -34.0995)
		(property "Reference" "C2T38"
			(at 0 0 0)
			(layer "B.SilkS")
			(hide yes)
			(effects
				(font
					(size 1.27 1.27)
				)
				(justify mirror)
			)
		)
		(property "Value" ""
			(at 0 0 0)
			(layer "B.Fab")
			(effects
				(font
					(size 1.27 1.27)
				)
				(justify mirror)
			)
		)
		(duplicate_pad_numbers_are_jumpers no)
		(fp_poly
			(pts
				(xy -0.3048 -0.1016) (xy -0.3048 0.9906) (xy 0.3048 0.9906) (xy 0.3048 -0.1016)
			)
			(stroke
				(width 0)
				(type default)
			)
			(fill no)
			(layer "B.CrtYd")
		)
		(fp_line
			(start -0.3048 -0.1016)
			(end 0.3048 -0.1016)
			(stroke
				(width 0.1)
				(type default)
			)
			(layer "B.Fab")
		)
		(fp_line
			(start -0.3048 0.9906)
			(end -0.3048 -0.1016)
			(stroke
				(width 0.1)
				(type default)
			)
			(layer "B.Fab")
		)
		(fp_line
			(start 0.3048 -0.1016)
			(end 0.3048 0.9906)
			(stroke
				(width 0.1)
				(type default)
			)
			(layer "B.Fab")
		)
		(fp_line
			(start 0.3048 0.9906)
			(end -0.3048 0.9906)
			(stroke
				(width 0.1)
				(type default)
			)
			(layer "B.Fab")
		)
		(pad "1" smd rect
			(at 0 0 180)
			(size 0.508 0.508)
			(layers "B.Cu" "B.Mask" "B.Paste")
			(net "P3V3_STBY_MNG_RMII")
		)
		(pad "2" smd rect
			(at 0 0.889 180)
			(size 0.508 0.508)
			(layers "B.Cu" "B.Mask" "B.Paste")
			(net "GND")
		)
		(zone
			(layer "B.Cu")
			(hatch none 0.5)
			(connect_pads
				(clearance 0)
			)
			(min_thickness 0.25)
			(keepout
				(tracks allowed)
				(vias not_allowed)
				(pads allowed)
				(copperpour not_allowed)
				(footprints allowed)
			)
			(placement
				(enabled no)
				(sheetname "")
			)
			(fill
				(thermal_gap 0.5)
				(thermal_bridge_width 0.5)
				(island_removal_mode 0)
			)
			(polygon
				(pts
					(xy 477.139 -33.8455) (xy 476.631 -33.8455) (xy 476.631 -33.4645) (xy 477.139 -33.4645)
				)
			)
		)
		(zone
			(layer "B.Cu")
			(hatch none 0.5)
			(connect_pads
				(clearance 0)
			)
			(min_thickness 0.25)
			(keepout
				(tracks not_allowed)
				(vias allowed)
				(pads allowed)
				(copperpour not_allowed)
				(footprints allowed)
			)
			(placement
				(enabled no)
				(sheetname "")
			)
			(fill
				(thermal_gap 0.5)
				(thermal_bridge_width 0.5)
				(island_removal_mode 0)
			)
			(polygon
				(pts
					(xy 477.139 -33.4645) (xy 476.631 -33.4645) (xy 476.631 -33.8455) (xy 477.139 -33.8455)
				)
			)
		)
	)
	(footprint ""
		(layer "B.Cu")
		(at 228.1174 -86.614 90)
		(property "Reference" "R4C5"
			(at 0.8382 -0.67818 90)
			(unlocked yes)
			(layer "B.SilkS")
			(effects
				(font
					(size 0.4064 0.254)
					(thickness 0.1524)
				)
				(justify left mirror)
			)
		)
		(property "Value" ""
			(at 0 0 90)
			(layer "B.Fab")
			(effects
				(font
					(size 1.27 1.27)
				)
				(justify mirror)
			)
		)
		(duplicate_pad_numbers_are_jumpers no)
		(fp_poly
			(pts
				(xy 0.2794 -0.1016) (xy -0.2794 -0.1016) (xy -0.2794 0.9906) (xy 0.2794 0.9906)
			)
			(stroke
				(width 0)
				(type default)
			)
			(fill no)
			(layer "B.CrtYd")
		)
		(fp_line
			(start 0.2794 -0.1016)
			(end 0.2794 0.9906)
			(stroke
				(width 0.1)
				(type default)
			)
			(layer "B.Fab")
		)
		(fp_line
			(start -0.2794 -0.1016)
			(end 0.2794 -0.1016)
			(stroke
				(width 0.1)
				(type default)
			)
			(layer "B.Fab")
		)
		(fp_line
			(start 0.2794 0.9906)
			(end -0.2794 0.9906)
			(stroke
				(width 0.1)
				(type default)
			)
			(layer "B.Fab")
		)
		(fp_line
			(start -0.2794 0.9906)
			(end -0.2794 -0.1016)
			(stroke
				(width 0.1)
				(type default)
			)
			(layer "B.Fab")
		)
		(pad "1" smd rect
			(at 0 0 270)
			(size 0.508 0.508)
			(layers "B.Cu" "B.Mask" "B.Paste")
			(net "VSENSE_PVSA_CPU0_P")
		)
		(pad "2" smd rect
			(at 0 0.889 270)
			(size 0.508 0.508)
			(layers "B.Cu" "B.Mask" "B.Paste")
			(net "PVSA_CPU0")
		)
		(zone
			(layer "B.Cu")
			(hatch none 0.5)
			(connect_pads
				(clearance 0)
			)
			(min_thickness 0.25)
			(keepout
				(tracks allowed)
				(vias not_allowed)
				(pads allowed)
				(copperpour not_allowed)
				(footprints allowed)
			)
			(placement
				(enabled no)
				(sheetname "")
			)
			(fill
				(thermal_gap 0.5)
				(thermal_bridge_width 0.5)
				(island_removal_mode 0)
			)
			(polygon
				(pts
					(xy 228.3714 -86.868) (xy 228.3714 -86.36) (xy 228.7524 -86.36) (xy 228.7524 -86.868)
				)
			)
		)
		(zone
			(layer "B.Cu")
			(hatch none 0.5)
			(connect_pads
				(clearance 0)
			)
			(min_thickness 0.25)
			(keepout
				(tracks not_allowed)
				(vias allowed)
				(pads allowed)
				(copperpour not_allowed)
				(footprints allowed)
			)
			(placement
				(enabled no)
				(sheetname "")
			)
			(fill
				(thermal_gap 0.5)
				(thermal_bridge_width 0.5)
				(island_removal_mode 0)
			)
			(polygon
				(pts
					(xy 228.7524 -86.868) (xy 228.7524 -86.36) (xy 228.3714 -86.36) (xy 228.3714 -86.868)
				)
			)
		)
	)
	(footprint ""
		(layer "B.Cu")
		(at 436.626 -52.3875)
		(property "Reference" "C2R18"
			(at 0 0 0)
			(layer "B.SilkS")
			(hide yes)
			(effects
				(font
					(size 1.27 1.27)
				)
				(justify mirror)
			)
		)
		(property "Value" ""
			(at 0 0 0)
			(layer "B.Fab")
			(effects
				(font
					(size 1.27 1.27)
				)
				(justify mirror)
			)
		)
		(duplicate_pad_numbers_are_jumpers no)
		(fp_poly
			(pts
				(xy -0.3048 -0.1016) (xy -0.3048 0.9906) (xy 0.3048 0.9906) (xy 0.3048 -0.1016)
			)
			(stroke
				(width 0)
				(type default)
			)
			(fill no)
			(layer "B.CrtYd")
		)
		(fp_line
			(start -0.3048 -0.1016)
			(end 0.3048 -0.1016)
			(stroke
				(width 0.1)
				(type default)
			)
			(layer "B.Fab")
		)
		(fp_line
			(start -0.3048 0.9906)
			(end -0.3048 -0.1016)
			(stroke
				(width 0.1)
				(type default)
			)
			(layer "B.Fab")
		)
		(fp_line
			(start 0.3048 -0.1016)
			(end 0.3048 0.9906)
			(stroke
				(width 0.1)
				(type default)
			)
			(layer "B.Fab")
		)
		(fp_line
			(start 0.3048 0.9906)
			(end -0.3048 0.9906)
			(stroke
				(width 0.1)
				(type default)
			)
			(layer "B.Fab")
		)
		(pad "1" smd rect
			(at 0 0 180)
			(size 0.508 0.508)
			(layers "B.Cu" "B.Mask" "B.Paste")
			(net "P12V_STBY")
		)
		(pad "2" smd rect
			(at 0 0.889 180)
			(size 0.508 0.508)
			(layers "B.Cu" "B.Mask" "B.Paste")
			(net "GND")
		)
		(zone
			(layer "B.Cu")
			(hatch none 0.5)
			(connect_pads
				(clearance 0)
			)
			(min_thickness 0.25)
			(keepout
				(tracks allowed)
				(vias not_allowed)
				(pads allowed)
				(copperpour not_allowed)
				(footprints allowed)
			)
			(placement
				(enabled no)
				(sheetname "")
			)
			(fill
				(thermal_gap 0.5)
				(thermal_bridge_width 0.5)
				(island_removal_mode 0)
			)
			(polygon
				(pts
					(xy 436.88 -52.1335) (xy 436.372 -52.1335) (xy 436.372 -51.7525) (xy 436.88 -51.7525)
				)
			)
		)
		(zone
			(layer "B.Cu")
			(hatch none 0.5)
			(connect_pads
				(clearance 0)
			)
			(min_thickness 0.25)
			(keepout
				(tracks not_allowed)
				(vias allowed)
				(pads allowed)
				(copperpour not_allowed)
				(footprints allowed)
			)
			(placement
				(enabled no)
				(sheetname "")
			)
			(fill
				(thermal_gap 0.5)
				(thermal_bridge_width 0.5)
				(island_removal_mode 0)
			)
			(polygon
				(pts
					(xy 436.88 -51.7525) (xy 436.372 -51.7525) (xy 436.372 -52.1335) (xy 436.88 -52.1335)
				)
			)
		)
	)
)
